(kicad_pcb
	(version 20260206)
	(generator "pcbnew")
	(generator_version "10.0")
	(general
		(thickness 1.6)
		(legacy_teardrops no)
	)
	(paper "A4")
	(title_block
		(title "Bryce Canyon_R.DPB_16317-1_OCP.brd")
		(comment 1 "Bryce Canyon / footprints 1053-1056 of 2099")
	)
	(layers
		(0 "F.Cu" signal "TOP")
		(4 "In1.Cu" signal "L2GND")
		(6 "In2.Cu" signal "L3")
		(8 "In3.Cu" signal "L4VCC")
		(10 "In4.Cu" signal "L5VCC")
		(12 "In5.Cu" signal "L6")
		(14 "In6.Cu" signal "L7GND")
		(2 "B.Cu" signal "BOTTOM")
		(9 "F.Adhes" user "F.Adhesive")
		(11 "B.Adhes" user "B.Adhesive")
		(13 "F.Paste" user "Package Geometry/Pastemask Top")
		(15 "B.Paste" user "Package Geometry/Pastemask Bottom")
		(5 "F.SilkS" user "Ref Des/Silkscreen Top")
		(7 "B.SilkS" user "Ref Des/Silkscreen Bottom")
		(1 "F.Mask" user "Board Geometry/Soldermask Top")
		(3 "B.Mask" user "Board Geometry/Soldermask Bottom")
		(17 "Dwgs.User" user "User.Drawings")
		(19 "Cmts.User" user "User.Comments")
		(21 "Eco1.User" user "User.Eco1")
		(23 "Eco2.User" user "User.Eco2")
		(25 "Edge.Cuts" user "Board Geometry/Outline")
		(27 "Margin" user)
		(31 "F.CrtYd" user "Package Geometry/Place Bound Top")
		(29 "B.CrtYd" user "Package Geometry/Place Bound Bottom")
		(35 "F.Fab" user "Ref Des/Assembly Top")
		(33 "B.Fab" user "Ref Des/Assembly Bottom")
	)
	(footprint ""
		(layer "F.Cu")
		(at 122.849894 -143.91005 -90)
		(property "Reference" "HDDSAS15"
			(at 0 0 270)
			(layer "F.SilkS")
			(hide yes)
			(effects
				(font
					(size 1.27 1.27)
				)
			)
		)
		(property "Value" "SKT-SAS15P-14P-45-GP"
			(at -20.7645 -8.9789 270)
			(unlocked yes)
			(layer "F.Fab")
			(hide yes)
			(effects
				(font
					(size 1.016 1.016)
					(thickness 0.1524)
				)
			)
		)
		(property "Device Type" "10120818-001C-TRLF"
			(at -20.7645 -10.5029 270)
			(unlocked yes)
			(layer "F.Fab")
			(hide yes)
			(effects
				(font
					(size 1.016 1.016)
					(thickness 0.1524)
				)
			)
		)
		(duplicate_pad_numbers_are_jumpers no)
		(fp_line
			(start 1.651 4.2926)
			(end 1.651 3.0099)
			(stroke
				(width 0.1524)
				(type default)
			)
			(layer "F.SilkS")
		)
		(fp_line
			(start 8.509 4.2926)
			(end 1.651 4.2926)
			(stroke
				(width 0.1524)
				(type default)
			)
			(layer "F.SilkS")
		)
		(fp_line
			(start -23.4188 3.0099)
			(end -23.4188 -3.2512)
			(stroke
				(width 0.1524)
				(type default)
			)
			(layer "F.SilkS")
		)
		(fp_line
			(start 1.651 3.0099)
			(end -23.4188 3.0099)
			(stroke
				(width 0.1524)
				(type default)
			)
			(layer "F.SilkS")
		)
		(fp_line
			(start 8.509 3.0099)
			(end 8.509 4.2926)
			(stroke
				(width 0.1524)
				(type default)
			)
			(layer "F.SilkS")
		)
		(fp_line
			(start 23.4188 3.0099)
			(end 8.509 3.0099)
			(stroke
				(width 0.1524)
				(type default)
			)
			(layer "F.SilkS")
		)
		(fp_line
			(start -23.4188 -3.2512)
			(end 23.4188 -3.2512)
			(stroke
				(width 0.1524)
				(type default)
			)
			(layer "F.SilkS")
		)
		(fp_line
			(start 23.4188 -3.2512)
			(end 23.4188 3.0099)
			(stroke
				(width 0.1524)
				(type default)
			)
			(layer "F.SilkS")
		)
		(fp_line
			(start 15.5067 -3.3401)
			(end 16.2687 -3.3401)
			(stroke
				(width 0.3302)
				(type default)
			)
			(layer "F.SilkS")
		)
		(fp_poly
			(pts
				(xy 15.868904 -3.230372) (xy 16.503904 -3.865372) (xy 15.233904 -3.865372)
			)
			(stroke
				(width 0)
				(type default)
			)
			(fill yes)
			(layer "F.SilkS")
		)
		(fp_poly
			(pts
				(xy -22.8727 -2.7559) (xy 22.8727 -2.7559) (xy 22.8727 2.7559) (xy 8.255 2.7559) (xy 8.255 3.5179)
				(xy 1.905 3.5179) (xy 1.905 2.7559) (xy -22.8727 2.7559)
			)
			(stroke
				(width 0)
				(type default)
			)
			(fill no)
			(layer "F.CrtYd")
		)
		(fp_poly
			(pts
				(xy 1.397 4.5466) (xy 1.397 3.2639) (xy -23.6728 3.2639) (xy -23.6728 -3.5052) (xy 23.6728 -3.5052)
				(xy 23.6728 -0.00635) (xy 22.8727 -0.00635) (xy 22.8727 -2.7559) (xy -22.8727 -2.7559) (xy -22.8727 2.7559)
				(xy 1.905 2.7559) (xy 1.905 3.5179) (xy 8.255 3.5179) (xy 8.255 2.7559) (xy 22.8727 2.7559) (xy 22.8727 0.00635)
				(xy 23.6728 0.00635) (xy 23.6728 3.2639) (xy 8.763 3.2639) (xy 8.763 4.5466)
			)
			(stroke
				(width 0)
				(type default)
			)
			(fill no)
			(layer "F.CrtYd")
		)
		(fp_poly
			(pts
				(xy 1.397 4.5466) (xy 1.397 3.2639) (xy -23.6728 3.2639) (xy -23.6728 -3.5052) (xy 23.6728 -3.5052)
				(xy 23.6728 3.2639) (xy 8.763 3.2639) (xy 8.763 4.5466)
			)
			(stroke
				(width 0)
				(type default)
			)
			(fill no)
			(layer "F.Fab")
		)
		(pad "" np_thru_hole circle
			(at -18.874994 0 270)
			(size 0.254 0.254)
			(drill 1.3462)
			(layers "*.Cu" "*.Mask")
			(clearance 0.9017)
			(thermal_gap 0.9017)
		)
		(pad "" np_thru_hole circle
			(at 18.874994 0 270)
			(size 0.254 0.254)
			(drill 0.9398)
			(layers "*.Cu" "*.Mask")
			(clearance 0.6985)
			(thermal_gap 0.6985)
		)
		(pad "G1" smd rect
			(at 21.874988 0 270)
			(size 2.5908 2.5908)
			(layers "F.Cu" "F.Mask" "F.Paste")
			(net "GND")
		)
		(pad "G2" smd rect
			(at -21.874988 0 270)
			(size 2.5908 2.5908)
			(layers "F.Cu" "F.Mask" "F.Paste")
			(net "GND")
		)
		(pad "P1" smd rect
			(at 1.905 -1.82499 270)
			(size 0.6096 2.3622)
			(layers "F.Cu" "F.Mask" "F.Paste")
			(net "Net_1729")
		)
		(pad "P2" smd rect
			(at 0.635 -1.82499 270)
			(size 0.6096 2.3622)
			(layers "F.Cu" "F.Mask" "F.Paste")
			(net "Net_1730")
		)
		(pad "P3" smd rect
			(at -0.635 -1.82499 270)
			(size 0.6096 2.3622)
			(layers "F.Cu" "F.Mask" "F.Paste")
			(net "Net_1731")
		)
		(pad "P4" smd rect
			(at -1.905 -1.82499 270)
			(size 0.6096 2.3622)
			(layers "F.Cu" "F.Mask" "F.Paste")
			(net "GND")
		)
		(pad "P5" smd rect
			(at -3.175 -1.82499 270)
			(size 0.6096 2.3622)
			(layers "F.Cu" "F.Mask" "F.Paste")
			(net "HDD_PRSNT_15")
		)
		(pad "P6" smd rect
			(at -4.445 -1.82499 270)
			(size 0.6096 2.3622)
			(layers "F.Cu" "F.Mask" "F.Paste")
			(net "GND")
		)
		(pad "P7" smd rect
			(at -5.715 -1.82499 270)
			(size 0.6096 2.3622)
			(layers "F.Cu" "F.Mask" "F.Paste")
			(net "5V_PRE_15")
		)
		(pad "P8" smd rect
			(at -6.985 -1.82499 270)
			(size 0.6096 2.3622)
			(layers "F.Cu" "F.Mask" "F.Paste")
			(net "P5V_HDD15")
		)
		(pad "P9" smd rect
			(at -8.255 -1.82499 270)
			(size 0.6096 2.3622)
			(layers "F.Cu" "F.Mask" "F.Paste")
			(net "P5V_HDD15")
		)
		(pad "P10" smd rect
			(at -9.525 -1.82499 270)
			(size 0.6096 2.3622)
			(layers "F.Cu" "F.Mask" "F.Paste")
			(net "GND")
		)
		(pad "P11" smd rect
			(at -10.795 -1.82499 270)
			(size 0.6096 2.3622)
			(layers "F.Cu" "F.Mask" "F.Paste")
			(net "ACT_HDD_15")
		)
		(pad "P12" smd rect
			(at -12.065 -1.82499 270)
			(size 0.6096 2.3622)
			(layers "F.Cu" "F.Mask" "F.Paste")
			(net "GND")
		)
		(pad "P13" smd rect
			(at -13.335 -1.82499 270)
			(size 0.6096 2.3622)
			(layers "F.Cu" "F.Mask" "F.Paste")
			(net "12V_PRE_15")
		)
		(pad "P14" smd rect
			(at -14.605 -1.82499 270)
			(size 0.6096 2.3622)
			(layers "F.Cu" "F.Mask" "F.Paste")
			(net "P12V_HDD15")
		)
		(pad "P15" smd rect
			(at -15.875 -1.82499 270)
			(size 0.6096 2.3622)
			(layers "F.Cu" "F.Mask" "F.Paste")
			(net "P12V_HDD15")
		)
		(pad "S1" smd rect
			(at 15.875 -1.82499 270)
			(size 0.6096 2.3622)
			(layers "F.Cu" "F.Mask" "F.Paste")
			(net "GND")
		)
		(pad "S2" smd rect
			(at 14.605 -1.82499 270)
			(size 0.6096 2.3622)
			(layers "F.Cu" "F.Mask" "F.Paste")
			(net "SAS_HDD_RX_P15")
		)
		(pad "S3" smd rect
			(at 13.335 -1.82499 270)
			(size 0.6096 2.3622)
			(layers "F.Cu" "F.Mask" "F.Paste")
			(net "SAS_HDD_RX_N15")
		)
		(pad "S4" smd rect
			(at 12.065 -1.82499 270)
			(size 0.6096 2.3622)
			(layers "F.Cu" "F.Mask" "F.Paste")
			(net "GND")
		)
		(pad "S5" smd rect
			(at 10.795 -1.82499 270)
			(size 0.6096 2.3622)
			(layers "F.Cu" "F.Mask" "F.Paste")
			(net "PHY_DRV_B_TO_SCC_B_15_DN")
		)
		(pad "S6" smd rect
			(at 9.525 -1.82499 270)
			(size 0.6096 2.3622)
			(layers "F.Cu" "F.Mask" "F.Paste")
			(net "PHY_DRV_B_TO_SCC_B_15_DP")
		)
		(pad "S7" smd rect
			(at 8.255 -1.82499 270)
			(size 0.6096 2.3622)
			(layers "F.Cu" "F.Mask" "F.Paste")
			(net "GND")
		)
		(pad "S8" smd rect
			(at 7.480046 2.845054 270)
			(size 0.508 2.3622)
			(layers "F.Cu" "F.Mask" "F.Paste")
			(net "GND")
		)
		(pad "S9" smd rect
			(at 6.679946 2.845054 270)
			(size 0.508 2.3622)
			(layers "F.Cu" "F.Mask" "F.Paste")
			(net "Net_438")
		)
		(pad "S10" smd rect
			(at 5.8801 2.845054 270)
			(size 0.508 2.3622)
			(layers "F.Cu" "F.Mask" "F.Paste")
			(net "Net_330")
		)
		(pad "S11" smd rect
			(at 5.08 2.845054 270)
			(size 0.508 2.3622)
			(layers "F.Cu" "F.Mask" "F.Paste")
			(net "GND")
		)
		(pad "S12" smd rect
			(at 4.2799 2.845054 270)
			(size 0.508 2.3622)
			(layers "F.Cu" "F.Mask" "F.Paste")
			(net "Net_366")
		)
		(pad "S13" smd rect
			(at 3.480054 2.845054 270)
			(size 0.508 2.3622)
			(layers "F.Cu" "F.Mask" "F.Paste")
			(net "Net_402")
		)
		(pad "S14" smd rect
			(at 2.679954 2.845054 270)
			(size 0.508 2.3622)
			(layers "F.Cu" "F.Mask" "F.Paste")
			(net "GND")
		)
		(zone
			(layer "F.Cu")
			(hatch none 0.5)
			(connect_pads
				(clearance 0)
			)
			(min_thickness 0.25)
			(keepout
				(tracks allowed)
				(vias not_allowed)
				(pads allowed)
				(copperpour not_allowed)
				(footprints allowed)
			)
			(placement
				(enabled no)
				(sheetname "")
			)
			(fill
				(thermal_gap 0.5)
				(thermal_bridge_width 0.5)
				(island_removal_mode 0)
			)
			(polygon
				(pts
					(xy 126.507494 -160.64865) (xy 119.433594 -160.64865) (xy 119.433594 -167.58285) (xy 120.538494 -167.58285)
					(xy 120.538494 -163.46805) (xy 125.161294 -163.46805) (xy 125.161294 -167.58285) (xy 126.507494 -167.58285)
				)
			)
		)
		(zone
			(layer "F.Cu")
			(hatch none 0.5)
			(connect_pads
				(clearance 0)
			)
			(min_thickness 0.25)
			(keepout
				(tracks not_allowed)
				(vias allowed)
				(pads allowed)
				(copperpour not_allowed)
				(footprints allowed)
			)
			(placement
				(enabled no)
				(sheetname "")
			)
			(fill
				(thermal_gap 0.5)
				(thermal_bridge_width 0.5)
				(island_removal_mode 0)
			)
			(polygon
				(pts
					(xy 126.507494 -160.64865) (xy 119.433594 -160.64865) (xy 119.433594 -167.58285) (xy 120.538494 -167.58285)
					(xy 120.538494 -163.46805) (xy 125.161294 -163.46805) (xy 125.161294 -167.58285) (xy 126.507494 -167.58285)
				)
			)
		)
		(zone
			(layer "F.Cu")
			(hatch none 0.5)
			(connect_pads
				(clearance 0)
			)
			(min_thickness 0.25)
			(keepout
				(tracks allowed)
				(vias not_allowed)
				(pads allowed)
				(copperpour not_allowed)
				(footprints allowed)
			)
			(placement
				(enabled no)
				(sheetname "")
			)
			(fill
				(thermal_gap 0.5)
				(thermal_bridge_width 0.5)
				(island_removal_mode 0)
			)
			(polygon
				(pts
					(xy 126.507494 -127.17145) (xy 119.433594 -127.17145) (xy 119.433594 -120.23725) (xy 120.538494 -120.23725)
					(xy 120.538494 -124.35205) (xy 125.161294 -124.35205) (xy 125.161294 -120.23725) (xy 126.507494 -120.23725)
				)
			)
		)
		(zone
			(layer "F.Cu")
			(hatch none 0.5)
			(connect_pads
				(clearance 0)
			)
			(min_thickness 0.25)
			(keepout
				(tracks not_allowed)
				(vias allowed)
				(pads allowed)
				(copperpour not_allowed)
				(footprints allowed)
			)
			(placement
				(enabled no)
				(sheetname "")
			)
			(fill
				(thermal_gap 0.5)
				(thermal_bridge_width 0.5)
				(island_removal_mode 0)
			)
			(polygon
				(pts
					(xy 126.507494 -127.17145) (xy 119.433594 -127.17145) (xy 119.433594 -120.23725) (xy 120.538494 -120.23725)
					(xy 120.538494 -124.35205) (xy 125.161294 -124.35205) (xy 125.161294 -120.23725) (xy 126.507494 -120.23725)
				)
			)
		)
		(zone
			(layers "F.Cu" "B.Cu" "In1.Cu" "In2.Cu" "In3.Cu" "In4.Cu" "In5.Cu" "In6.Cu")
			(hatch none 0.5)
			(connect_pads
				(clearance 0)
			)
			(min_thickness 0.25)
			(keepout
				(tracks not_allowed)
				(vias allowed)
				(pads allowed)
				(copperpour not_allowed)
				(footprints allowed)
			)
			(placement
				(enabled no)
				(sheetname "")
			)
			(fill
				(thermal_gap 0.5)
				(thermal_bridge_width 0.5)
				(island_removal_mode 0)
			)
			(polygon
				(pts
					(arc
						(start 123.624594 -125.035056)
						(mid 122.075194 -125.035056)
						(end 123.624594 -125.035056)
					)
				)
			)
		)
		(zone
			(layers "F.Cu" "B.Cu" "In1.Cu" "In2.Cu" "In3.Cu" "In4.Cu" "In5.Cu" "In6.Cu")
			(hatch none 0.5)
			(connect_pads
				(clearance 0)
			)
			(min_thickness 0.25)
			(keepout
				(tracks not_allowed)
				(vias allowed)
				(pads allowed)
				(copperpour not_allowed)
				(footprints allowed)
			)
			(placement
				(enabled no)
				(sheetname "")
			)
			(fill
				(thermal_gap 0.5)
				(thermal_bridge_width 0.5)
				(island_removal_mode 0)
			)
			(polygon
				(pts
					(arc
						(start 123.827794 -162.785044)
						(mid 121.871994 -162.785044)
						(end 123.827794 -162.785044)
					)
				)
			)
		)
	)
	(footprint ""
		(layer "F.Cu")
		(at 86.106 -133.4262 -90)
		(property "Reference" "R400"
			(at 0 0 270)
			(layer "F.SilkS")
			(hide yes)
			(effects
				(font
					(size 1.27 1.27)
				)
			)
		)
		(property "Value" "1KR2F-3-GP"
			(at 0.064008 -3.993896 270)
			(unlocked yes)
			(layer "F.Fab")
			(hide yes)
			(effects
				(font
					(size 1.016 1.016)
					(thickness 0.1524)
				)
			)
		)
		(property "Device Type" "R402H16"
			(at 0.064008 -5.517896 270)
			(unlocked yes)
			(layer "F.Fab")
			(hide yes)
			(effects
				(font
					(size 1.016 1.016)
					(thickness 0.1524)
				)
			)
		)
		(duplicate_pad_numbers_are_jumpers no)
		(fp_line
			(start -0.508 -0.9398)
			(end -0.508 0.9398)
			(stroke
				(width 0.1524)
				(type default)
			)
			(layer "F.SilkS")
		)
		(fp_line
			(start 0.508 -0.9398)
			(end -0.508 -0.9398)
			(stroke
				(width 0.1524)
				(type default)
			)
			(layer "F.SilkS")
		)
		(fp_rect
			(start -0.508 0.9398)
			(end 0.508 -0.9398)
			(stroke
				(width 0)
				(type default)
			)
			(fill no)
			(layer "F.CrtYd")
		)
		(fp_rect
			(start -0.508 0.9398)
			(end 0.508 -0.9398)
			(stroke
				(width 0)
				(type default)
			)
			(fill no)
			(layer "F.Fab")
		)
		(pad "1" smd custom
			(at 0 -0.4445 270)
			(size 0.1397 0.1397)
			(layers "F.Cu" "F.Mask" "F.Paste")
			(net "P3V3_STBY_B")
			(options
				(clearance outline)
				(anchor circle)
			)
			(primitives
				(gr_poly
					(pts
						(arc
							(start -0.1778 -0.2794)
							(mid -0.249642 -0.249642)
							(end -0.2794 -0.1778)
						)
						(arc
							(start -0.2794 0.1778)
							(mid -0.249642 0.249642)
							(end -0.1778 0.2794)
						)
						(arc
							(start 0.1778 0.2794)
							(mid 0.249642 0.249642)
							(end 0.2794 0.1778)
						)
						(arc
							(start 0.2794 -0.1778)
							(mid 0.249642 -0.249642)
							(end 0.1778 -0.2794)
						)
					)
					(width 0)
					(fill yes)
				)
			)
		)
		(pad "2" smd custom
			(at 0 0.4445 270)
			(size 0.1397 0.1397)
			(layers "F.Cu" "F.Mask" "F.Paste")
			(net "SW_PWR_R_HDD14")
			(options
				(clearance outline)
				(anchor circle)
			)
			(primitives
				(gr_poly
					(pts
						(arc
							(start -0.1778 -0.2794)
							(mid -0.249642 -0.249642)
							(end -0.2794 -0.1778)
						)
						(arc
							(start -0.2794 0.1778)
							(mid -0.249642 0.249642)
							(end -0.1778 0.2794)
						)
						(arc
							(start 0.1778 0.2794)
							(mid 0.249642 0.249642)
							(end 0.2794 0.1778)
						)
						(arc
							(start 0.2794 -0.1778)
							(mid 0.249642 -0.249642)
							(end 0.1778 -0.2794)
						)
					)
					(width 0)
					(fill yes)
				)
			)
		)
	)
	(footprint ""
		(layer "F.Cu")
		(at 363.601 -13.589)
		(property "Reference" "R795"
			(at 0 0 0)
			(layer "F.SilkS")
			(hide yes)
			(effects
				(font
					(size 1.27 1.27)
				)
			)
		)
		(property "Value" "4K7R2F-GP"
			(at 0.064008 -3.993896 0)
			(unlocked yes)
			(layer "F.Fab")
			(hide yes)
			(effects
				(font
					(size 1.016 1.016)
					(thickness 0.1524)
				)
			)
		)
		(property "Device Type" "R402H16"
			(at 0.064008 -5.517896 0)
			(unlocked yes)
			(layer "F.Fab")
			(hide yes)
			(effects
				(font
					(size 1.016 1.016)
					(thickness 0.1524)
				)
			)
		)
		(duplicate_pad_numbers_are_jumpers no)
		(fp_line
			(start -0.508 -0.9398)
			(end -0.508 0.9398)
			(stroke
				(width 0.1524)
				(type default)
			)
			(layer "F.SilkS")
		)
		(fp_line
			(start 0.508 -0.9398)
			(end -0.508 -0.9398)
			(stroke
				(width 0.1524)
				(type default)
			)
			(layer "F.SilkS")
		)
		(fp_rect
			(start -0.508 0.9398)
			(end 0.508 -0.9398)
			(stroke
				(width 0)
				(type default)
			)
			(fill no)
			(layer "F.CrtYd")
		)
		(fp_rect
			(start -0.508 0.9398)
			(end 0.508 -0.9398)
			(stroke
				(width 0)
				(type default)
			)
			(fill no)
			(layer "F.Fab")
		)
		(pad "1" smd custom
			(at 0 -0.4445)
			(size 0.1397 0.1397)
			(layers "F.Cu" "F.Mask" "F.Paste")
			(net "SW_PWR_R_HDD31")
			(options
				(clearance outline)
				(anchor circle)
			)
			(primitives
				(gr_poly
					(pts
						(arc
							(start -0.1778 -0.2794)
							(mid -0.249642 -0.249642)
							(end -0.2794 -0.1778)
						)
						(arc
							(start -0.2794 0.1778)
							(mid -0.249642 0.249642)
							(end -0.1778 0.2794)
						)
						(arc
							(start 0.1778 0.2794)
							(mid 0.249642 0.249642)
							(end 0.2794 0.1778)
						)
						(arc
							(start 0.2794 -0.1778)
							(mid 0.249642 -0.249642)
							(end 0.1778 -0.2794)
						)
					)
					(width 0)
					(fill yes)
				)
			)
		)
		(pad "2" smd custom
			(at 0 0.4445)
			(size 0.1397 0.1397)
			(layers "F.Cu" "F.Mask" "F.Paste")
			(net "GND")
			(options
				(clearance outline)
				(anchor circle)
			)
			(primitives
				(gr_poly
					(pts
						(arc
							(start -0.1778 -0.2794)
							(mid -0.249642 -0.249642)
							(end -0.2794 -0.1778)
						)
						(arc
							(start -0.2794 0.1778)
							(mid -0.249642 0.249642)
							(end -0.1778 0.2794)
						)
						(arc
							(start 0.1778 0.2794)
							(mid 0.249642 0.249642)
							(end 0.2794 0.1778)
						)
						(arc
							(start 0.2794 -0.1778)
							(mid 0.249642 -0.249642)
							(end 0.1778 -0.2794)
						)
					)
					(width 0)
					(fill yes)
				)
			)
		)
	)
	(footprint ""
		(layer "F.Cu")
		(at 333.502 -160.02 180)
		(property "Reference" "C270"
			(at 0 0 180)
			(layer "F.SilkS")
			(hide yes)
			(effects
				(font
					(size 1.27 1.27)
				)
			)
		)
		(property "Value" "SC4D7U25V5KX-1-GP"
			(at -0.0762 -6.1214 180)
			(unlocked yes)
			(layer "F.Fab")
			(hide yes)
			(effects
				(font
					(size 1.016 1.016)
					(thickness 0.1524)
				)
			)
		)
		(property "Device Type" "C805H58"
			(at -0.0762 -8.1534 180)
			(unlocked yes)
			(layer "F.Fab")
			(hide yes)
			(effects
				(font
					(size 1.016 1.016)
					(thickness 0.1524)
				)
			)
		)
		(duplicate_pad_numbers_are_jumpers no)
		(fp_line
			(start 0.635 0)
			(end -0.635 0)
			(stroke
				(width 0.508)
				(type default)
			)
			(layer "F.SilkS")
		)
		(fp_rect
			(start -0.9652 1.778)
			(end 0.9652 -1.778)
			(stroke
				(width 0)
				(type default)
			)
			(fill no)
			(layer "F.CrtYd")
		)
		(fp_poly
			(pts
				(xy -0.9652 -1.778) (xy 0.9652 -1.778) (xy 0.9652 1.778) (xy -0.9652 1.778)
			)
			(stroke
				(width 0)
				(type default)
			)
			(fill no)
			(layer "F.Fab")
		)
		(pad "1" smd rect
			(at 0 -0.9652 180)
			(size 1.397 1.143)
			(layers "F.Cu" "F.Mask" "F.Paste")
			(net "P12V_HDD18")
		)
		(pad "2" smd rect
			(at 0 0.9652 180)
			(size 1.397 1.143)
			(layers "F.Cu" "F.Mask" "F.Paste")
			(net "GND")
		)
	)
)
